# T6G (Grand Teton) — schematic netlist excerpt (pin names and nets, part order shuffled) for the footprints in the layout excerpt that follows; sources: Cadence DE-HDL packaged netlist, KiCad conversion of 04192023_DAF0TMB3IC0_F0TG_MB_C_brd_V02_OCP.brd

R570  Q_RES  0 5% CHIP  pkg 0402LF  page 55 : A = CPU1_SPD_HOST_CTRL_N ; B = CPU1_SPD_HOST_CTRL_R_N
R6105  Q_RES  0 5% CHIP  pkg 0402LF  page 174 : A = JTAG_CPU0_TDO_CPU1_TDI_R1 ; B = JTAG_CPU0_TDO_CPU1_TDI

(kicad_pcb
	(version 20260206)
	(generator "pcbnew")
	(generator_version "10.0")
	(general
		(thickness 1.6)
		(legacy_teardrops no)
	)
	(paper "A4")
	(title_block
		(title "04192023_DAF0TMB3IC0_F0TG_MB_C_brd_V02_OCP.brd")
		(comment 1 "Grand Teton / footprints 4570-4571 of 8354")
	)
	(layers
		(0 "F.Cu" signal "TOP")
		(4 "In1.Cu" signal "GND")
		(6 "In2.Cu" signal "IN1")
		(8 "In3.Cu" signal "GND1")
		(10 "In4.Cu" signal "IN2")
		(12 "In5.Cu" signal "GND2")
		(14 "In6.Cu" signal "IN3")
		(16 "In7.Cu" signal "GND3")
		(18 "In8.Cu" signal "VCC")
		(20 "In9.Cu" signal "VCC1")
		(22 "In10.Cu" signal "GND4")
		(24 "In11.Cu" signal "IN4")
		(26 "In12.Cu" signal "GND5")
		(28 "In13.Cu" signal "IN5")
		(30 "In14.Cu" signal "GND6")
		(32 "In15.Cu" signal "IN6")
		(34 "In16.Cu" signal "GND7")
		(2 "B.Cu" signal "BOTTOM")
		(9 "F.Adhes" user "F.Adhesive")
		(11 "B.Adhes" user "B.Adhesive")
		(13 "F.Paste" user "Package Geometry/Pastemask Top")
		(15 "B.Paste" user "Package Geometry/Pastemask Bottom")
		(5 "F.SilkS" user "Ref Des/Silkscreen Top")
		(7 "B.SilkS" user "Ref Des/Silkscreen Bottom")
		(1 "F.Mask" user "Board Geometry/Soldermask Top")
		(3 "B.Mask" user "Board Geometry/Soldermask Bottom")
		(17 "Dwgs.User" user "User.Drawings")
		(19 "Cmts.User" user "User.Comments")
		(21 "Eco1.User" user "User.Eco1")
		(23 "Eco2.User" user "User.Eco2")
		(25 "Edge.Cuts" user "Board Geometry/Outline")
		(27 "Margin" user)
		(31 "F.CrtYd" user "Package Geometry/Place Bound Top")
		(29 "B.CrtYd" user "Package Geometry/Place Bound Bottom")
		(35 "F.Fab" user "Ref Des/Assembly Top")
		(33 "B.Fab" user "Ref Des/Assembly Bottom")
	)
	(footprint ""
		(layer "F.Cu")
		(at 143.385286 -321.694556 -90)
		(property "Reference" "R570"
			(at 0 0 270)
			(layer "F.SilkS")
			(hide yes)
			(effects
				(font
					(size 1.27 1.27)
				)
			)
		)
		(property "Value" ""
			(at 0 0 270)
			(layer "F.Fab")
			(effects
				(font
					(size 1.27 1.27)
				)
			)
		)
		(duplicate_pad_numbers_are_jumpers no)
		(fp_line
			(start -0.7874 0.4064)
			(end -0.7874 -0.4064)
			(stroke
				(width 0.1524)
				(type default)
			)
			(layer "F.SilkS")
		)
		(fp_line
			(start 0.7874 0.4064)
			(end -0.7874 0.4064)
			(stroke
				(width 0.1524)
				(type default)
			)
			(layer "F.SilkS")
		)
		(fp_line
			(start -0.7874 -0.4064)
			(end 0.7874 -0.4064)
			(stroke
				(width 0.1524)
				(type default)
			)
			(layer "F.SilkS")
		)
		(fp_line
			(start 0.7874 -0.4064)
			(end 0.7874 0.4064)
			(stroke
				(width 0.1524)
				(type default)
			)
			(layer "F.SilkS")
		)
		(fp_line
			(start -0.67945 0.3048)
			(end -0.67945 -0.305054)
			(stroke
				(width 0.1)
				(type default)
			)
			(layer "F.Fab")
		)
		(fp_line
			(start -0.12065 0.3048)
			(end -0.67945 0.3048)
			(stroke
				(width 0.1)
				(type default)
			)
			(layer "F.Fab")
		)
		(fp_line
			(start 0.120396 0.3048)
			(end 0.120396 0.2794)
			(stroke
				(width 0.1)
				(type default)
			)
			(layer "F.Fab")
		)
		(fp_line
			(start 0.67945 0.3048)
			(end 0.120396 0.3048)
			(stroke
				(width 0.1)
				(type default)
			)
			(layer "F.Fab")
		)
		(fp_line
			(start -0.12065 0.2794)
			(end -0.12065 0.3048)
			(stroke
				(width 0.1)
				(type default)
			)
			(layer "F.Fab")
		)
		(fp_line
			(start 0.120396 0.2794)
			(end -0.12065 0.2794)
			(stroke
				(width 0.1)
				(type default)
			)
			(layer "F.Fab")
		)
		(fp_line
			(start -0.12065 -0.2794)
			(end 0.12065 -0.2794)
			(stroke
				(width 0.1)
				(type default)
			)
			(layer "F.Fab")
		)
		(fp_line
			(start 0.12065 -0.2794)
			(end 0.12065 -0.3048)
			(stroke
				(width 0.1)
				(type default)
			)
			(layer "F.Fab")
		)
		(fp_line
			(start 0.12065 -0.3048)
			(end 0.67945 -0.3048)
			(stroke
				(width 0.1)
				(type default)
			)
			(layer "F.Fab")
		)
		(fp_line
			(start 0.67945 -0.3048)
			(end 0.67945 0.3048)
			(stroke
				(width 0.1)
				(type default)
			)
			(layer "F.Fab")
		)
		(fp_line
			(start -0.67945 -0.305054)
			(end -0.12065 -0.305054)
			(stroke
				(width 0.1)
				(type default)
			)
			(layer "F.Fab")
		)
		(fp_line
			(start -0.12065 -0.305054)
			(end -0.12065 -0.2794)
			(stroke
				(width 0.1)
				(type default)
			)
			(layer "F.Fab")
		)
		(pad "1" smd circle
			(at -0.40005 0 270)
			(size 0 0)
			(layers "F.Cu" "F.Mask" "F.Paste")
			(net "CPU1_SPD_HOST_CTRL_N")
		)
		(pad "2" smd circle
			(at 0.40005 0 270)
			(size 0 0)
			(layers "F.Cu" "F.Mask" "F.Paste")
			(net "CPU1_SPD_HOST_CTRL_R_N")
		)
	)
	(footprint ""
		(layer "F.Cu")
		(at 229.5652 -152.954228 180)
		(property "Reference" "R6105"
			(at 0 0 180)
			(layer "F.SilkS")
			(hide yes)
			(effects
				(font
					(size 1.27 1.27)
				)
			)
		)
		(property "Value" ""
			(at 0 0 180)
			(layer "F.Fab")
			(effects
				(font
					(size 1.27 1.27)
				)
			)
		)
		(duplicate_pad_numbers_are_jumpers no)
		(fp_line
			(start 0.7874 0.4064)
			(end -0.7874 0.4064)
			(stroke
				(width 0.1524)
				(type default)
			)
			(layer "F.SilkS")
		)
		(fp_line
			(start 0.7874 -0.4064)
			(end 0.7874 0.4064)
			(stroke
				(width 0.1524)
				(type default)
			)
			(layer "F.SilkS")
		)
		(fp_line
			(start -0.7874 0.4064)
			(end -0.7874 -0.4064)
			(stroke
				(width 0.1524)
				(type default)
			)
			(layer "F.SilkS")
		)
		(fp_line
			(start -0.7874 -0.4064)
			(end 0.7874 -0.4064)
			(stroke
				(width 0.1524)
				(type default)
			)
			(layer "F.SilkS")
		)
		(fp_line
			(start 0.67945 0.3048)
			(end 0.120396 0.3048)
			(stroke
				(width 0.1)
				(type default)
			)
			(layer "F.Fab")
		)
		(fp_line
			(start 0.67945 -0.3048)
			(end 0.67945 0.3048)
			(stroke
				(width 0.1)
				(type default)
			)
			(layer "F.Fab")
		)
		(fp_line
			(start 0.12065 -0.2794)
			(end 0.12065 -0.3048)
			(stroke
				(width 0.1)
				(type default)
			)
			(layer "F.Fab")
		)
		(fp_line
			(start 0.12065 -0.3048)
			(end 0.67945 -0.3048)
			(stroke
				(width 0.1)
				(type default)
			)
			(layer "F.Fab")
		)
		(fp_line
			(start 0.120396 0.3048)
			(end 0.120396 0.2794)
			(stroke
				(width 0.1)
				(type default)
			)
			(layer "F.Fab")
		)
		(fp_line
			(start 0.120396 0.2794)
			(end -0.12065 0.2794)
			(stroke
				(width 0.1)
				(type default)
			)
			(layer "F.Fab")
		)
		(fp_line
			(start -0.12065 0.3048)
			(end -0.67945 0.3048)
			(stroke
				(width 0.1)
				(type default)
			)
			(layer "F.Fab")
		)
		(fp_line
			(start -0.12065 0.2794)
			(end -0.12065 0.3048)
			(stroke
				(width 0.1)
				(type default)
			)
			(layer "F.Fab")
		)
		(fp_line
			(start -0.12065 -0.2794)
			(end 0.12065 -0.2794)
			(stroke
				(width 0.1)
				(type default)
			)
			(layer "F.Fab")
		)
		(fp_line
			(start -0.12065 -0.305054)
			(end -0.12065 -0.2794)
			(stroke
				(width 0.1)
				(type default)
			)
			(layer "F.Fab")
		)
		(fp_line
			(start -0.67945 0.3048)
			(end -0.67945 -0.305054)
			(stroke
				(width 0.1)
				(type default)
			)
			(layer "F.Fab")
		)
		(fp_line
			(start -0.67945 -0.305054)
			(end -0.12065 -0.305054)
			(stroke
				(width 0.1)
				(type default)
			)
			(layer "F.Fab")
		)
		(pad "1" smd circle
			(at -0.40005 0 180)
			(size 0 0)
			(layers "F.Cu" "F.Mask" "F.Paste")
			(net "JTAG_CPU0_TDO_CPU1_TDI_R1")
		)
		(pad "2" smd circle
			(at 0.40005 0 180)
			(size 0 0)
			(layers "F.Cu" "F.Mask" "F.Paste")
			(net "JTAG_CPU0_TDO_CPU1_TDI")
		)
	)
)
